(kicad_pcb
	(version 20260206)
	(generator "pcbnew")
	(generator_version "10.0")
	(general
		(thickness 1.6)
		(legacy_teardrops no)
	)
	(paper "A4")
	(title_block
		(title "peb — Lightning_PEB_BRD.brd")
		(comment 1 "Lightning (Wiwynn / Facebook NVMe JBOF) / footprints 1738-1744 of 2563")
	)
	(layers
		(0 "F.Cu" signal "TOP")
		(4 "In1.Cu" signal "L2GND")
		(6 "In2.Cu" signal "L3")
		(8 "In3.Cu" signal "L4VCC")
		(10 "In4.Cu" signal "L5VCC")
		(12 "In5.Cu" signal "L6")
		(14 "In6.Cu" signal "L7GND")
		(2 "B.Cu" signal "BOTTOM")
		(9 "F.Adhes" user "F.Adhesive")
		(11 "B.Adhes" user "B.Adhesive")
		(13 "F.Paste" user "Package Geometry/Pastemask Top")
		(15 "B.Paste" user "Package Geometry/Pastemask Bottom")
		(5 "F.SilkS" user "Ref Des/Silkscreen Top")
		(7 "B.SilkS" user "Ref Des/Silkscreen Bottom")
		(1 "F.Mask" user "Board Geometry/Soldermask Top")
		(3 "B.Mask" user "Board Geometry/Soldermask Bottom")
		(17 "Dwgs.User" user "User.Drawings")
		(19 "Cmts.User" user "User.Comments")
		(21 "Eco1.User" user "User.Eco1")
		(23 "Eco2.User" user "User.Eco2")
		(25 "Edge.Cuts" user "Board Geometry/Outline")
		(27 "Margin" user)
		(31 "F.CrtYd" user "Package Geometry/Place Bound Top")
		(29 "B.CrtYd" user "Package Geometry/Place Bound Bottom")
		(35 "F.Fab" user "Ref Des/Assembly Top")
		(33 "B.Fab" user "Ref Des/Assembly Bottom")
	)
	(footprint ""
		(layer "B.Cu")
		(at 182.13578 -7.5438 -90)
		(property "Reference" "R2952"
			(at 0 0 90)
			(layer "B.SilkS")
			(hide yes)
			(effects
				(font
					(size 1.27 1.27)
				)
				(justify mirror)
			)
		)
		(property "Value" "0R2J-2-GP"
			(at -0.064008 -3.993896 270)
			(unlocked yes)
			(layer "B.Fab")
			(hide yes)
			(effects
				(font
					(size 1.016 1.016)
					(thickness 0.1524)
				)
				(justify mirror)
			)
		)
		(property "Device Type" "R402H16"
			(at -0.064008 -5.517896 270)
			(unlocked yes)
			(layer "B.Fab")
			(hide yes)
			(effects
				(font
					(size 1.016 1.016)
					(thickness 0.1524)
				)
				(justify mirror)
			)
		)
		(duplicate_pad_numbers_are_jumpers no)
		(fp_line
			(start -0.508 -0.9398)
			(end 0.508 -0.9398)
			(stroke
				(width 0.1524)
				(type default)
			)
			(layer "B.SilkS")
		)
		(fp_line
			(start 0.508 -0.9398)
			(end 0.508 0.9398)
			(stroke
				(width 0.1524)
				(type default)
			)
			(layer "B.SilkS")
		)
		(fp_rect
			(start 0.508 0.9398)
			(end -0.508 -0.9398)
			(stroke
				(width 0)
				(type default)
			)
			(fill no)
			(layer "B.CrtYd")
		)
		(fp_rect
			(start 0.508 0.9398)
			(end -0.508 -0.9398)
			(stroke
				(width 0)
				(type default)
			)
			(fill no)
			(layer "B.Fab")
		)
		(pad "1" smd custom
			(at 0 -0.4445 90)
			(size 0.1397 0.1397)
			(layers "B.Cu" "B.Mask" "B.Paste")
			(net "PCIE_REFCLK_H2_N")
			(options
				(clearance outline)
				(anchor circle)
			)
			(primitives
				(gr_poly
					(pts
						(arc
							(start -0.1778 0.2794)
							(mid -0.249642 0.249642)
							(end -0.2794 0.1778)
						)
						(arc
							(start -0.2794 -0.1778)
							(mid -0.249642 -0.249642)
							(end -0.1778 -0.2794)
						)
						(arc
							(start 0.1778 -0.2794)
							(mid 0.249642 -0.249642)
							(end 0.2794 -0.1778)
						)
						(arc
							(start 0.2794 0.1778)
							(mid 0.249642 0.249642)
							(end 0.1778 0.2794)
						)
					)
					(width 0)
					(fill yes)
				)
			)
		)
		(pad "2" smd custom
			(at 0 0.4445 90)
			(size 0.1397 0.1397)
			(layers "B.Cu" "B.Mask" "B.Paste")
			(net "PCIE_REFCLK_H2_N_R")
			(options
				(clearance outline)
				(anchor circle)
			)
			(primitives
				(gr_poly
					(pts
						(arc
							(start -0.1778 0.2794)
							(mid -0.249642 0.249642)
							(end -0.2794 0.1778)
						)
						(arc
							(start -0.2794 -0.1778)
							(mid -0.249642 -0.249642)
							(end -0.1778 -0.2794)
						)
						(arc
							(start 0.1778 -0.2794)
							(mid 0.249642 -0.249642)
							(end 0.2794 -0.1778)
						)
						(arc
							(start 0.2794 0.1778)
							(mid 0.249642 0.249642)
							(end 0.1778 0.2794)
						)
					)
					(width 0)
					(fill yes)
				)
			)
		)
	)
	(footprint ""
		(layer "B.Cu")
		(at 251.587 -42.0116 -90)
		(property "Reference" "C588"
			(at 0 0 90)
			(layer "B.SilkS")
			(hide yes)
			(effects
				(font
					(size 1.27 1.27)
				)
				(justify mirror)
			)
		)
		(property "Value" "SCD1U16V1KX-1-GP"
			(at 2.8321 -1.7399 270)
			(unlocked yes)
			(layer "B.Fab")
			(hide yes)
			(effects
				(font
					(size 1.016 1.016)
					(thickness 0.1524)
				)
				(justify mirror)
			)
		)
		(property "Device Type" "C0201H13"
			(at 2.8321 -3.2639 270)
			(unlocked yes)
			(layer "B.Fab")
			(hide yes)
			(effects
				(font
					(size 1.016 1.016)
					(thickness 0.1524)
				)
				(justify mirror)
			)
		)
		(duplicate_pad_numbers_are_jumpers no)
		(fp_rect
			(start 0.2794 0.6477)
			(end -0.2794 -0.6477)
			(stroke
				(width 0)
				(type default)
			)
			(fill no)
			(layer "B.CrtYd")
		)
		(fp_rect
			(start 0.2794 0.6477)
			(end -0.2794 -0.6477)
			(stroke
				(width 0)
				(type default)
			)
			(fill no)
			(layer "B.Fab")
		)
		(pad "1" smd custom
			(at 0 -0.2794 90)
			(size 0.0762 0.0762)
			(layers "B.Cu" "B.Mask" "B.Paste")
			(net "DUT_AVD_PCIE")
			(options
				(clearance outline)
				(anchor circle)
			)
			(primitives
				(gr_poly
					(pts
						(arc
							(start 0.1524 0.127)
							(mid 0.137521 0.162921)
							(end 0.1016 0.1778)
						)
						(arc
							(start -0.1016 0.1778)
							(mid -0.137521 0.162921)
							(end -0.1524 0.127)
						)
						(arc
							(start -0.1524 -0.127)
							(mid -0.137521 -0.162921)
							(end -0.1016 -0.1778)
						)
						(arc
							(start 0.1016 -0.1778)
							(mid 0.137521 -0.162921)
							(end 0.1524 -0.127)
						)
					)
					(width 0)
					(fill yes)
				)
			)
		)
		(pad "2" smd custom
			(at 0 0.2794 90)
			(size 0.0762 0.0762)
			(layers "B.Cu" "B.Mask" "B.Paste")
			(net "GND")
			(options
				(clearance outline)
				(anchor circle)
			)
			(primitives
				(gr_poly
					(pts
						(arc
							(start 0.1524 0.127)
							(mid 0.137521 0.162921)
							(end 0.1016 0.1778)
						)
						(arc
							(start -0.1016 0.1778)
							(mid -0.137521 0.162921)
							(end -0.1524 0.127)
						)
						(arc
							(start -0.1524 -0.127)
							(mid -0.137521 -0.162921)
							(end -0.1016 -0.1778)
						)
						(arc
							(start 0.1016 -0.1778)
							(mid 0.137521 -0.162921)
							(end 0.1524 -0.127)
						)
					)
					(width 0)
					(fill yes)
				)
			)
		)
	)
	(footprint ""
		(layer "B.Cu")
		(at 13.462 -78.0034 90)
		(property "Reference" "C635"
			(at 0 0 90)
			(layer "B.SilkS")
			(hide yes)
			(effects
				(font
					(size 1.27 1.27)
				)
				(justify mirror)
			)
		)
		(property "Value" "SCD1U16V2KX-3GP"
			(at -1.1811 -2.7051 90)
			(unlocked yes)
			(layer "B.Fab")
			(hide yes)
			(effects
				(font
					(size 1.016 1.016)
					(thickness 0.1524)
				)
				(justify mirror)
			)
		)
		(property "Device Type" "C402H22"
			(at -1.1811 -4.2291 90)
			(unlocked yes)
			(layer "B.Fab")
			(hide yes)
			(effects
				(font
					(size 1.016 1.016)
					(thickness 0.1524)
				)
				(justify mirror)
			)
		)
		(duplicate_pad_numbers_are_jumpers no)
		(fp_rect
			(start 0.4318 0.9525)
			(end -0.4318 -0.9525)
			(stroke
				(width 0)
				(type default)
			)
			(fill no)
			(layer "B.CrtYd")
		)
		(fp_rect
			(start 0.4318 0.9525)
			(end -0.4318 -0.9525)
			(stroke
				(width 0)
				(type default)
			)
			(fill no)
			(layer "B.Fab")
		)
		(pad "1" smd custom
			(at 0 -0.4445 270)
			(size 0.1524 0.1524)
			(layers "B.Cu" "B.Mask" "B.Paste")
			(net "P0V9_I210")
			(options
				(clearance outline)
				(anchor circle)
			)
			(primitives
				(gr_poly
					(pts
						(arc
							(start 0.3048 0.2032)
							(mid 0.275042 0.275042)
							(end 0.2032 0.3048)
						)
						(arc
							(start -0.2032 0.3048)
							(mid -0.275042 0.275042)
							(end -0.3048 0.2032)
						)
						(arc
							(start -0.3048 -0.2032)
							(mid -0.275042 -0.275042)
							(end -0.2032 -0.3048)
						)
						(arc
							(start 0.2032 -0.3048)
							(mid 0.275042 -0.275042)
							(end 0.3048 -0.2032)
						)
					)
					(width 0)
					(fill yes)
				)
			)
		)
		(pad "2" smd custom
			(at 0 0.4445 270)
			(size 0.1524 0.1524)
			(layers "B.Cu" "B.Mask" "B.Paste")
			(net "GND")
			(options
				(clearance outline)
				(anchor circle)
			)
			(primitives
				(gr_poly
					(pts
						(arc
							(start 0.3048 0.2032)
							(mid 0.275042 0.275042)
							(end 0.2032 0.3048)
						)
						(arc
							(start -0.2032 0.3048)
							(mid -0.275042 0.275042)
							(end -0.3048 0.2032)
						)
						(arc
							(start -0.3048 -0.2032)
							(mid -0.275042 -0.275042)
							(end -0.2032 -0.3048)
						)
						(arc
							(start 0.2032 -0.3048)
							(mid 0.275042 -0.275042)
							(end 0.3048 -0.2032)
						)
					)
					(width 0)
					(fill yes)
				)
			)
		)
	)
	(footprint ""
		(layer "B.Cu")
		(at 229.049072 -41.012872 90)
		(property "Reference" "C576"
			(at 0 0 90)
			(layer "B.SilkS")
			(hide yes)
			(effects
				(font
					(size 1.27 1.27)
				)
				(justify mirror)
			)
		)
		(property "Value" "SCD1U16V1KX-1-GP"
			(at 2.8321 -1.7399 90)
			(unlocked yes)
			(layer "B.Fab")
			(hide yes)
			(effects
				(font
					(size 1.016 1.016)
					(thickness 0.1524)
				)
				(justify mirror)
			)
		)
		(property "Device Type" "C0201H13"
			(at 2.8321 -3.2639 90)
			(unlocked yes)
			(layer "B.Fab")
			(hide yes)
			(effects
				(font
					(size 1.016 1.016)
					(thickness 0.1524)
				)
				(justify mirror)
			)
		)
		(duplicate_pad_numbers_are_jumpers no)
		(fp_rect
			(start 0.2794 0.6477)
			(end -0.2794 -0.6477)
			(stroke
				(width 0)
				(type default)
			)
			(fill no)
			(layer "B.CrtYd")
		)
		(fp_rect
			(start 0.2794 0.6477)
			(end -0.2794 -0.6477)
			(stroke
				(width 0)
				(type default)
			)
			(fill no)
			(layer "B.Fab")
		)
		(pad "1" smd custom
			(at 0 -0.2794 270)
			(size 0.0762 0.0762)
			(layers "B.Cu" "B.Mask" "B.Paste")
			(net "DUT_AVD_PCIE")
			(options
				(clearance outline)
				(anchor circle)
			)
			(primitives
				(gr_poly
					(pts
						(arc
							(start 0.1524 0.127)
							(mid 0.137521 0.162921)
							(end 0.1016 0.1778)
						)
						(arc
							(start -0.1016 0.1778)
							(mid -0.137521 0.162921)
							(end -0.1524 0.127)
						)
						(arc
							(start -0.1524 -0.127)
							(mid -0.137521 -0.162921)
							(end -0.1016 -0.1778)
						)
						(arc
							(start 0.1016 -0.1778)
							(mid 0.137521 -0.162921)
							(end 0.1524 -0.127)
						)
					)
					(width 0)
					(fill yes)
				)
			)
		)
		(pad "2" smd custom
			(at 0 0.2794 270)
			(size 0.0762 0.0762)
			(layers "B.Cu" "B.Mask" "B.Paste")
			(net "GND")
			(options
				(clearance outline)
				(anchor circle)
			)
			(primitives
				(gr_poly
					(pts
						(arc
							(start 0.1524 0.127)
							(mid 0.137521 0.162921)
							(end 0.1016 0.1778)
						)
						(arc
							(start -0.1016 0.1778)
							(mid -0.137521 0.162921)
							(end -0.1524 0.127)
						)
						(arc
							(start -0.1524 -0.127)
							(mid -0.137521 -0.162921)
							(end -0.1016 -0.1778)
						)
						(arc
							(start 0.1016 -0.1778)
							(mid 0.137521 -0.162921)
							(end 0.1524 -0.127)
						)
					)
					(width 0)
					(fill yes)
				)
			)
		)
	)
	(footprint ""
		(layer "B.Cu")
		(at 245.1354 -51.9938 90)
		(property "Reference" "C443"
			(at 0 0 90)
			(layer "B.SilkS")
			(hide yes)
			(effects
				(font
					(size 1.27 1.27)
				)
				(justify mirror)
			)
		)
		(property "Value" "SCD1U16V1KX-1-GP"
			(at 2.8321 -1.7399 90)
			(unlocked yes)
			(layer "B.Fab")
			(hide yes)
			(effects
				(font
					(size 1.016 1.016)
					(thickness 0.1524)
				)
				(justify mirror)
			)
		)
		(property "Device Type" "C0201H13"
			(at 2.8321 -3.2639 90)
			(unlocked yes)
			(layer "B.Fab")
			(hide yes)
			(effects
				(font
					(size 1.016 1.016)
					(thickness 0.1524)
				)
				(justify mirror)
			)
		)
		(duplicate_pad_numbers_are_jumpers no)
		(fp_rect
			(start 0.2794 0.6477)
			(end -0.2794 -0.6477)
			(stroke
				(width 0)
				(type default)
			)
			(fill no)
			(layer "B.CrtYd")
		)
		(fp_rect
			(start 0.2794 0.6477)
			(end -0.2794 -0.6477)
			(stroke
				(width 0)
				(type default)
			)
			(fill no)
			(layer "B.Fab")
		)
		(pad "1" smd custom
			(at 0 -0.2794 270)
			(size 0.0762 0.0762)
			(layers "B.Cu" "B.Mask" "B.Paste")
			(net "DUT_VDD")
			(options
				(clearance outline)
				(anchor circle)
			)
			(primitives
				(gr_poly
					(pts
						(arc
							(start 0.1524 0.127)
							(mid 0.137521 0.162921)
							(end 0.1016 0.1778)
						)
						(arc
							(start -0.1016 0.1778)
							(mid -0.137521 0.162921)
							(end -0.1524 0.127)
						)
						(arc
							(start -0.1524 -0.127)
							(mid -0.137521 -0.162921)
							(end -0.1016 -0.1778)
						)
						(arc
							(start 0.1016 -0.1778)
							(mid 0.137521 -0.162921)
							(end 0.1524 -0.127)
						)
					)
					(width 0)
					(fill yes)
				)
			)
		)
		(pad "2" smd custom
			(at 0 0.2794 270)
			(size 0.0762 0.0762)
			(layers "B.Cu" "B.Mask" "B.Paste")
			(net "GND")
			(options
				(clearance outline)
				(anchor circle)
			)
			(primitives
				(gr_poly
					(pts
						(arc
							(start 0.1524 0.127)
							(mid 0.137521 0.162921)
							(end 0.1016 0.1778)
						)
						(arc
							(start -0.1016 0.1778)
							(mid -0.137521 0.162921)
							(end -0.1524 0.127)
						)
						(arc
							(start -0.1524 -0.127)
							(mid -0.137521 -0.162921)
							(end -0.1016 -0.1778)
						)
						(arc
							(start 0.1016 -0.1778)
							(mid 0.137521 -0.162921)
							(end 0.1524 -0.127)
						)
					)
					(width 0)
					(fill yes)
				)
			)
		)
	)
	(footprint ""
		(layer "B.Cu")
		(at 61.341 -122.428 -90)
		(property "Reference" "R599"
			(at 0 0 90)
			(layer "B.SilkS")
			(hide yes)
			(effects
				(font
					(size 1.27 1.27)
				)
				(justify mirror)
			)
		)
		(property "Value" "4K7R2F-GP"
			(at -0.064008 -3.993896 270)
			(unlocked yes)
			(layer "B.Fab")
			(hide yes)
			(effects
				(font
					(size 1.016 1.016)
					(thickness 0.1524)
				)
				(justify mirror)
			)
		)
		(property "Device Type" "R402H16"
			(at -0.064008 -5.517896 270)
			(unlocked yes)
			(layer "B.Fab")
			(hide yes)
			(effects
				(font
					(size 1.016 1.016)
					(thickness 0.1524)
				)
				(justify mirror)
			)
		)
		(duplicate_pad_numbers_are_jumpers no)
		(fp_line
			(start -0.508 -0.9398)
			(end 0.508 -0.9398)
			(stroke
				(width 0.1524)
				(type default)
			)
			(layer "B.SilkS")
		)
		(fp_line
			(start 0.508 -0.9398)
			(end 0.508 0.9398)
			(stroke
				(width 0.1524)
				(type default)
			)
			(layer "B.SilkS")
		)
		(fp_rect
			(start 0.508 0.9398)
			(end -0.508 -0.9398)
			(stroke
				(width 0)
				(type default)
			)
			(fill no)
			(layer "B.CrtYd")
		)
		(fp_rect
			(start 0.508 0.9398)
			(end -0.508 -0.9398)
			(stroke
				(width 0)
				(type default)
			)
			(fill no)
			(layer "B.Fab")
		)
		(pad "1" smd custom
			(at 0 -0.4445 90)
			(size 0.1397 0.1397)
			(layers "B.Cu" "B.Mask" "B.Paste")
			(net "BMC_I2C4_MINI4_SDA_S")
			(options
				(clearance outline)
				(anchor circle)
			)
			(primitives
				(gr_poly
					(pts
						(arc
							(start -0.1778 0.2794)
							(mid -0.249642 0.249642)
							(end -0.2794 0.1778)
						)
						(arc
							(start -0.2794 -0.1778)
							(mid -0.249642 -0.249642)
							(end -0.1778 -0.2794)
						)
						(arc
							(start 0.1778 -0.2794)
							(mid 0.249642 -0.249642)
							(end 0.2794 -0.1778)
						)
						(arc
							(start 0.2794 0.1778)
							(mid 0.249642 0.249642)
							(end 0.1778 0.2794)
						)
					)
					(width 0)
					(fill yes)
				)
			)
		)
		(pad "2" smd custom
			(at 0 0.4445 90)
			(size 0.1397 0.1397)
			(layers "B.Cu" "B.Mask" "B.Paste")
			(net "P3V3_STBY")
			(options
				(clearance outline)
				(anchor circle)
			)
			(primitives
				(gr_poly
					(pts
						(arc
							(start -0.1778 0.2794)
							(mid -0.249642 0.249642)
							(end -0.2794 0.1778)
						)
						(arc
							(start -0.2794 -0.1778)
							(mid -0.249642 -0.249642)
							(end -0.1778 -0.2794)
						)
						(arc
							(start 0.1778 -0.2794)
							(mid 0.249642 -0.249642)
							(end 0.2794 -0.1778)
						)
						(arc
							(start 0.2794 0.1778)
							(mid 0.249642 0.249642)
							(end 0.1778 0.2794)
						)
					)
					(width 0)
					(fill yes)
				)
			)
		)
	)
	(footprint ""
		(layer "B.Cu")
		(at 75.102212 -186.545474)
		(property "Reference" "R3203"
			(at 0 0 0)
			(layer "B.SilkS")
			(hide yes)
			(effects
				(font
					(size 1.27 1.27)
				)
				(justify mirror)
			)
		)
		(property "Value" "0R2J-2-GP"
			(at -0.064008 -3.993896 0)
			(unlocked yes)
			(layer "B.Fab")
			(hide yes)
			(effects
				(font
					(size 1.016 1.016)
					(thickness 0.1524)
				)
				(justify mirror)
			)
		)
		(property "Device Type" "R402H16"
			(at -0.064008 -5.517896 0)
			(unlocked yes)
			(layer "B.Fab")
			(hide yes)
			(effects
				(font
					(size 1.016 1.016)
					(thickness 0.1524)
				)
				(justify mirror)
			)
		)
		(duplicate_pad_numbers_are_jumpers no)
		(fp_line
			(start -0.508 -0.9398)
			(end 0.508 -0.9398)
			(stroke
				(width 0.1524)
				(type default)
			)
			(layer "B.SilkS")
		)
		(fp_line
			(start 0.508 -0.9398)
			(end 0.508 0.9398)
			(stroke
				(width 0.1524)
				(type default)
			)
			(layer "B.SilkS")
		)
		(fp_rect
			(start 0.508 0.9398)
			(end -0.508 -0.9398)
			(stroke
				(width 0)
				(type default)
			)
			(fill no)
			(layer "B.CrtYd")
		)
		(fp_rect
			(start 0.508 0.9398)
			(end -0.508 -0.9398)
			(stroke
				(width 0)
				(type default)
			)
			(fill no)
			(layer "B.Fab")
		)
		(pad "1" smd custom
			(at 0 -0.4445 180)
			(size 0.1397 0.1397)
			(layers "B.Cu" "B.Mask" "B.Paste")
			(net "SSD_PERST_Y0")
			(options
				(clearance outline)
				(anchor circle)
			)
			(primitives
				(gr_poly
					(pts
						(arc
							(start -0.1778 0.2794)
							(mid -0.249642 0.249642)
							(end -0.2794 0.1778)
						)
						(arc
							(start -0.2794 -0.1778)
							(mid -0.249642 -0.249642)
							(end -0.1778 -0.2794)
						)
						(arc
							(start 0.1778 -0.2794)
							(mid 0.249642 -0.249642)
							(end 0.2794 -0.1778)
						)
						(arc
							(start 0.2794 0.1778)
							(mid 0.249642 0.249642)
							(end 0.1778 0.2794)
						)
					)
					(width 0)
					(fill yes)
				)
			)
		)
		(pad "2" smd custom
			(at 0 0.4445 180)
			(size 0.1397 0.1397)
			(layers "B.Cu" "B.Mask" "B.Paste")
			(net "SSD_PERST#0_R")
			(options
				(clearance outline)
				(anchor circle)
			)
			(primitives
				(gr_poly
					(pts
						(arc
							(start -0.1778 0.2794)
							(mid -0.249642 0.249642)
							(end -0.2794 0.1778)
						)
						(arc
							(start -0.2794 -0.1778)
							(mid -0.249642 -0.249642)
							(end -0.1778 -0.2794)
						)
						(arc
							(start 0.1778 -0.2794)
							(mid 0.249642 -0.249642)
							(end 0.2794 -0.1778)
						)
						(arc
							(start 0.2794 0.1778)
							(mid 0.249642 0.249642)
							(end 0.1778 0.2794)
						)
					)
					(width 0)
					(fill yes)
				)
			)
		)
	)
)
